(kicad_pcb
	(version 20260206)
	(generator "pcbnew")
	(generator_version "10.0")
	(general
		(thickness 1.6)
		(legacy_teardrops no)
	)
	(paper "A4")
	(title_block
		(title "panther-plus-userver — 13130-1b_20150205.brd")
		(comment 1 "Honey Badger (Wiwynn) / footprint 894 of 1509 (DIMM1), pads 93-99 of 210")
	)
	(layers
		(0 "F.Cu" signal "TOP")
		(4 "In1.Cu" signal "L2")
		(6 "In2.Cu" signal "L3")
		(8 "In3.Cu" signal "L4")
		(10 "In4.Cu" signal "L5")
		(12 "In5.Cu" signal "L6")
		(14 "In6.Cu" signal "L7")
		(16 "In7.Cu" signal "L8")
		(18 "In8.Cu" signal "L9")
		(20 "In9.Cu" signal "L10")
		(22 "In10.Cu" signal "L11")
		(2 "B.Cu" signal "BOTTOM")
		(9 "F.Adhes" user "F.Adhesive")
		(11 "B.Adhes" user "B.Adhesive")
		(13 "F.Paste" user "Package Geometry/Pastemask Top")
		(15 "B.Paste" user "Package Geometry/Pastemask Bottom")
		(5 "F.SilkS" user "Ref Des/Silkscreen Top")
		(7 "B.SilkS" user "Ref Des/Silkscreen Bottom")
		(1 "F.Mask" user "Board Geometry/Soldermask Top")
		(3 "B.Mask" user "Board Geometry/Soldermask Bottom")
		(17 "Dwgs.User" user "User.Drawings")
		(19 "Cmts.User" user "User.Comments")
		(21 "Eco1.User" user "User.Eco1")
		(23 "Eco2.User" user "User.Eco2")
		(25 "Edge.Cuts" user "Board Geometry/Outline")
		(27 "Margin" user)
		(31 "F.CrtYd" user "Package Geometry/Place Bound Top")
		(29 "B.CrtYd" user "Package Geometry/Place Bound Bottom")
		(35 "F.Fab" user "Ref Des/Assembly Top")
		(33 "B.Fab" user "Ref Des/Assembly Bottom")
	)
	(footprint ""
		(layer "B.Cu")
		(at 158.500064 -66.699892 180)
		(property "Reference" "DIMM1"
			(at 0 0 0)
			(layer "B.SilkS")
			(hide yes)
			(effects
				(font
					(size 1.27 1.27)
				)
				(justify mirror)
			)
		)
		(property "Value" "DDR3-204P-142-COLAY-1-GP-U"
			(at 41.312338 -16.676878 180)
			(unlocked yes)
			(layer "B.Fab")
			(hide yes)
			(effects
				(font
					(size 1.016 1.016)
					(thickness 0.1524)
				)
				(justify mirror)
			)
		)
		(property "Device Type" "AS0A626-J8R6-7H-COLAY-1"
			(at 41.312338 -18.200878 180)
			(unlocked yes)
			(layer "B.Fab")
			(hide yes)
			(effects
				(font
					(size 1.016 1.016)
					(thickness 0.1524)
				)
				(justify mirror)
			)
		)
		(duplicate_pad_numbers_are_jumpers no)
		(pad "91" smd custom
			(at -2.249932 -4.100068)
			(size 0.1143 0.1143)
			(layers "B.Cu" "B.Mask" "B.Paste")
			(net "M_A_BS2")
			(options
				(clearance outline)
				(anchor circle)
			)
			(primitives
				(gr_poly
					(pts
						(xy 0 -0.9017) (xy -0.03175 -0.89916) (xy -0.0635 -0.889) (xy -0.09144 -0.87376) (xy -0.11684 -0.85344)
						(xy -0.13716 -0.82804) (xy -0.1524 -0.8001) (xy -0.16256 -0.76835) (xy -0.1651 -0.7366) (xy -0.1651 -0.19685)
						(xy -0.17272 -0.18923) (xy -0.17907 -0.18034) (xy -0.18669 -0.17145) (xy -0.19177 -0.16256) (xy -0.19812 -0.15367)
						(xy -0.20828 -0.13335) (xy -0.21971 -0.10287) (xy -0.22225 -0.09271) (xy -0.22479 -0.08128) (xy -0.22606 -0.07112)
						(xy -0.2286 -0.05969) (xy -0.2286 -0.01651) (xy -0.22606 -0.00508) (xy -0.22479 0.00508) (xy -0.22225 0.01651)
						(xy -0.21971 0.02667) (xy -0.20828 0.05715) (xy -0.19812 0.07747) (xy -0.19177 0.08636) (xy -0.18669 0.09525)
						(xy -0.17907 0.10414) (xy -0.17272 0.11303) (xy -0.1651 0.12065) (xy -0.1651 0.7366) (xy -0.16256 0.76835)
						(xy -0.1524 0.8001) (xy -0.13716 0.82804) (xy -0.11684 0.85344) (xy -0.09144 0.87376) (xy -0.0635 0.889)
						(xy -0.03175 0.89916) (xy 0 0.9017) (xy 0.03175 0.89916) (xy 0.0635 0.889) (xy 0.09144 0.87376)
						(xy 0.11684 0.85344) (xy 0.13716 0.82804) (xy 0.1524 0.8001) (xy 0.16256 0.76835) (xy 0.1651 0.7366)
						(xy 0.1651 0.11938) (xy 0.17272 0.11176) (xy 0.19812 0.0762) (xy 0.2032 0.06604) (xy 0.20701 0.05715)
						(xy 0.21209 0.04699) (xy 0.2159 0.03683) (xy 0.21844 0.02667) (xy 0.22225 0.01524) (xy 0.22352 0.00508)
						(xy 0.22606 -0.00508) (xy 0.22733 -0.01651) (xy 0.22733 -0.02667) (xy 0.2286 -0.0381) (xy 0.22733 -0.04953)
						(xy 0.22733 -0.05969) (xy 0.22606 -0.07112) (xy 0.22352 -0.08128) (xy 0.22225 -0.09144) (xy 0.21844 -0.10287)
						(xy 0.2159 -0.11303) (xy 0.21209 -0.12319) (xy 0.20701 -0.13335) (xy 0.2032 -0.14224) (xy 0.19812 -0.1524)
						(xy 0.17272 -0.18796) (xy 0.1651 -0.19558) (xy 0.1651 -0.7366) (xy 0.16256 -0.76835) (xy 0.1524 -0.8001)
						(xy 0.13716 -0.82804) (xy 0.11684 -0.85344) (xy 0.09144 -0.87376) (xy 0.0635 -0.889) (xy 0.03175 -0.89916)
					)
					(width 0)
					(fill yes)
				)
			)
		)
		(pad "92" smd custom
			(at -1.949958 4.100068)
			(size 0.1143 0.1143)
			(layers "B.Cu" "B.Mask" "B.Paste")
			(net "M_A_MA9")
			(options
				(clearance outline)
				(anchor circle)
			)
			(primitives
				(gr_poly
					(pts
						(xy 0 -0.9017) (xy -0.03175 -0.89916) (xy -0.0635 -0.889) (xy -0.09144 -0.87376) (xy -0.11684 -0.85344)
						(xy -0.13716 -0.82804) (xy -0.1524 -0.8001) (xy -0.16256 -0.76835) (xy -0.1651 -0.7366) (xy -0.1651 -0.11938)
						(xy -0.17272 -0.11176) (xy -0.19812 -0.0762) (xy -0.2032 -0.06604) (xy -0.20701 -0.05715) (xy -0.21209 -0.04699)
						(xy -0.2159 -0.03683) (xy -0.21844 -0.02667) (xy -0.22225 -0.01524) (xy -0.22352 -0.00508) (xy -0.22606 0.00508)
						(xy -0.22733 0.01651) (xy -0.22733 0.02667) (xy -0.2286 0.0381) (xy -0.22733 0.04953) (xy -0.22733 0.05969)
						(xy -0.22606 0.07112) (xy -0.22352 0.08128) (xy -0.22225 0.09144) (xy -0.21844 0.10287) (xy -0.2159 0.11303)
						(xy -0.21209 0.12319) (xy -0.20701 0.13335) (xy -0.2032 0.14224) (xy -0.19812 0.1524) (xy -0.17272 0.18796)
						(xy -0.1651 0.19558) (xy -0.1651 0.7366) (xy -0.16256 0.76835) (xy -0.1524 0.8001) (xy -0.13716 0.82804)
						(xy -0.11684 0.85344) (xy -0.09144 0.87376) (xy -0.0635 0.889) (xy -0.03175 0.89916) (xy 0 0.9017)
						(xy 0.03175 0.89916) (xy 0.0635 0.889) (xy 0.09144 0.87376) (xy 0.11684 0.85344) (xy 0.13716 0.82804)
						(xy 0.1524 0.8001) (xy 0.16256 0.76835) (xy 0.1651 0.7366) (xy 0.1651 0.19685) (xy 0.17272 0.18923)
						(xy 0.17907 0.18034) (xy 0.18669 0.17145) (xy 0.19177 0.16256) (xy 0.19812 0.15367) (xy 0.20828 0.13335)
						(xy 0.21971 0.10287) (xy 0.22225 0.09271) (xy 0.22479 0.08128) (xy 0.22606 0.07112) (xy 0.2286 0.05969)
						(xy 0.2286 0.01651) (xy 0.22606 0.00508) (xy 0.22479 -0.00508) (xy 0.22225 -0.01651) (xy 0.21971 -0.02667)
						(xy 0.20828 -0.05715) (xy 0.19812 -0.07747) (xy 0.19177 -0.08636) (xy 0.18669 -0.09525) (xy 0.17907 -0.10414)
						(xy 0.17272 -0.11303) (xy 0.1651 -0.12065) (xy 0.1651 -0.7366) (xy 0.16256 -0.76835) (xy 0.1524 -0.8001)
						(xy 0.13716 -0.82804) (xy 0.11684 -0.85344) (xy 0.09144 -0.87376) (xy 0.0635 -0.889) (xy 0.03175 -0.89916)
					)
					(width 0)
					(fill yes)
				)
			)
		)
		(pad "93" smd custom
			(at -1.649984 -4.100068)
			(size 0.1143 0.1143)
			(layers "B.Cu" "B.Mask" "B.Paste")
			(net "PV_VDDR")
			(options
				(clearance outline)
				(anchor circle)
			)
			(primitives
				(gr_poly
					(pts
						(xy 0 -0.9017) (xy -0.03175 -0.89916) (xy -0.0635 -0.889) (xy -0.09144 -0.87376) (xy -0.11684 -0.85344)
						(xy -0.13716 -0.82804) (xy -0.1524 -0.8001) (xy -0.16256 -0.76835) (xy -0.1651 -0.7366) (xy -0.1651 -0.44958)
						(xy -0.17272 -0.44196) (xy -0.19812 -0.4064) (xy -0.2032 -0.39624) (xy -0.20701 -0.38735) (xy -0.21209 -0.37719)
						(xy -0.2159 -0.36703) (xy -0.21844 -0.35687) (xy -0.22225 -0.34544) (xy -0.22352 -0.33528) (xy -0.22606 -0.32512)
						(xy -0.22733 -0.31369) (xy -0.22733 -0.30353) (xy -0.2286 -0.2921) (xy -0.22733 -0.28067) (xy -0.22733 -0.27051)
						(xy -0.22606 -0.25908) (xy -0.22352 -0.24892) (xy -0.22225 -0.23876) (xy -0.21844 -0.22733) (xy -0.2159 -0.21717)
						(xy -0.21209 -0.20701) (xy -0.20701 -0.19685) (xy -0.2032 -0.18796) (xy -0.19812 -0.1778) (xy -0.17272 -0.14224)
						(xy -0.1651 -0.13462) (xy -0.1651 0.7366) (xy -0.16256 0.76835) (xy -0.1524 0.8001) (xy -0.13716 0.82804)
						(xy -0.11684 0.85344) (xy -0.09144 0.87376) (xy -0.0635 0.889) (xy -0.03175 0.89916) (xy 0 0.9017)
						(xy 0.03175 0.89916) (xy 0.0635 0.889) (xy 0.09144 0.87376) (xy 0.11684 0.85344) (xy 0.13716 0.82804)
						(xy 0.1524 0.8001) (xy 0.16256 0.76835) (xy 0.1651 0.7366) (xy 0.1651 -0.13462) (xy 0.17272 -0.14224)
						(xy 0.19812 -0.1778) (xy 0.2032 -0.18796) (xy 0.20701 -0.19685) (xy 0.21209 -0.20701) (xy 0.2159 -0.21717)
						(xy 0.21844 -0.22733) (xy 0.22225 -0.23876) (xy 0.22352 -0.24892) (xy 0.22606 -0.25908) (xy 0.22733 -0.27051)
						(xy 0.22733 -0.28067) (xy 0.2286 -0.2921) (xy 0.22733 -0.30353) (xy 0.22733 -0.31369) (xy 0.22606 -0.32512)
						(xy 0.22352 -0.33528) (xy 0.22225 -0.34544) (xy 0.21844 -0.35687) (xy 0.2159 -0.36703) (xy 0.21209 -0.37719)
						(xy 0.20701 -0.38735) (xy 0.2032 -0.39624) (xy 0.19812 -0.4064) (xy 0.17272 -0.44196) (xy 0.1651 -0.44958)
						(xy 0.1651 -0.7366) (xy 0.16256 -0.76835) (xy 0.1524 -0.8001) (xy 0.13716 -0.82804) (xy 0.11684 -0.85344)
						(xy 0.09144 -0.87376) (xy 0.0635 -0.889) (xy 0.03175 -0.89916)
					)
					(width 0)
					(fill yes)
				)
			)
		)
		(pad "94" smd custom
			(at -1.35001 4.100068)
			(size 0.1143 0.1143)
			(layers "B.Cu" "B.Mask" "B.Paste")
			(net "PV_VDDR")
			(options
				(clearance outline)
				(anchor circle)
			)
			(primitives
				(gr_poly
					(pts
						(xy 0 -0.9017) (xy -0.03175 -0.89916) (xy -0.0635 -0.889) (xy -0.09144 -0.87376) (xy -0.11684 -0.85344)
						(xy -0.13716 -0.82804) (xy -0.1524 -0.8001) (xy -0.16256 -0.76835) (xy -0.1651 -0.7366) (xy -0.1651 0.13462)
						(xy -0.17272 0.14224) (xy -0.19812 0.1778) (xy -0.2032 0.18796) (xy -0.20701 0.19685) (xy -0.21209 0.20701)
						(xy -0.2159 0.21717) (xy -0.21844 0.22733) (xy -0.22225 0.23876) (xy -0.22352 0.24892) (xy -0.22606 0.25908)
						(xy -0.22733 0.27051) (xy -0.22733 0.28067) (xy -0.2286 0.2921) (xy -0.22733 0.30353) (xy -0.22733 0.31369)
						(xy -0.22606 0.32512) (xy -0.22352 0.33528) (xy -0.22225 0.34544) (xy -0.21844 0.35687) (xy -0.2159 0.36703)
						(xy -0.21209 0.37719) (xy -0.20701 0.38735) (xy -0.2032 0.39624) (xy -0.19812 0.4064) (xy -0.17272 0.44196)
						(xy -0.1651 0.44958) (xy -0.1651 0.7366) (xy -0.16256 0.76835) (xy -0.1524 0.8001) (xy -0.13716 0.82804)
						(xy -0.11684 0.85344) (xy -0.09144 0.87376) (xy -0.0635 0.889) (xy -0.03175 0.89916) (xy 0 0.9017)
						(xy 0.03175 0.89916) (xy 0.0635 0.889) (xy 0.09144 0.87376) (xy 0.11684 0.85344) (xy 0.13716 0.82804)
						(xy 0.1524 0.8001) (xy 0.16256 0.76835) (xy 0.1651 0.7366) (xy 0.1651 0.44958) (xy 0.17272 0.44196)
						(xy 0.19812 0.4064) (xy 0.2032 0.39624) (xy 0.20701 0.38735) (xy 0.21209 0.37719) (xy 0.2159 0.36703)
						(xy 0.21844 0.35687) (xy 0.22225 0.34544) (xy 0.22352 0.33528) (xy 0.22606 0.32512) (xy 0.22733 0.31369)
						(xy 0.22733 0.30353) (xy 0.2286 0.2921) (xy 0.22733 0.28067) (xy 0.22733 0.27051) (xy 0.22606 0.25908)
						(xy 0.22352 0.24892) (xy 0.22225 0.23876) (xy 0.21844 0.22733) (xy 0.2159 0.21717) (xy 0.21209 0.20701)
						(xy 0.20701 0.19685) (xy 0.2032 0.18796) (xy 0.19812 0.1778) (xy 0.17272 0.14224) (xy 0.1651 0.13462)
						(xy 0.1651 -0.7366) (xy 0.16256 -0.76835) (xy 0.1524 -0.8001) (xy 0.13716 -0.82804) (xy 0.11684 -0.85344)
						(xy 0.09144 -0.87376) (xy 0.0635 -0.889) (xy 0.03175 -0.89916)
					)
					(width 0)
					(fill yes)
				)
			)
		)
		(pad "95" smd custom
			(at -1.050036 -4.100068)
			(size 0.1143 0.1143)
			(layers "B.Cu" "B.Mask" "B.Paste")
			(net "M_A_MA12")
			(options
				(clearance outline)
				(anchor circle)
			)
			(primitives
				(gr_poly
					(pts
						(xy 0 -0.9017) (xy -0.03175 -0.89916) (xy -0.0635 -0.889) (xy -0.09144 -0.87376) (xy -0.11684 -0.85344)
						(xy -0.13716 -0.82804) (xy -0.1524 -0.8001) (xy -0.16256 -0.76835) (xy -0.1651 -0.7366) (xy -0.1651 -0.19685)
						(xy -0.17272 -0.18923) (xy -0.17907 -0.18034) (xy -0.18669 -0.17145) (xy -0.19177 -0.16256) (xy -0.19812 -0.15367)
						(xy -0.20828 -0.13335) (xy -0.21971 -0.10287) (xy -0.22225 -0.09271) (xy -0.22479 -0.08128) (xy -0.22606 -0.07112)
						(xy -0.2286 -0.05969) (xy -0.2286 -0.01651) (xy -0.22606 -0.00508) (xy -0.22479 0.00508) (xy -0.22225 0.01651)
						(xy -0.21971 0.02667) (xy -0.20828 0.05715) (xy -0.19812 0.07747) (xy -0.19177 0.08636) (xy -0.18669 0.09525)
						(xy -0.17907 0.10414) (xy -0.17272 0.11303) (xy -0.1651 0.12065) (xy -0.1651 0.7366) (xy -0.16256 0.76835)
						(xy -0.1524 0.8001) (xy -0.13716 0.82804) (xy -0.11684 0.85344) (xy -0.09144 0.87376) (xy -0.0635 0.889)
						(xy -0.03175 0.89916) (xy 0 0.9017) (xy 0.03175 0.89916) (xy 0.0635 0.889) (xy 0.09144 0.87376)
						(xy 0.11684 0.85344) (xy 0.13716 0.82804) (xy 0.1524 0.8001) (xy 0.16256 0.76835) (xy 0.1651 0.7366)
						(xy 0.1651 0.11938) (xy 0.17272 0.11176) (xy 0.19812 0.0762) (xy 0.2032 0.06604) (xy 0.20701 0.05715)
						(xy 0.21209 0.04699) (xy 0.2159 0.03683) (xy 0.21844 0.02667) (xy 0.22225 0.01524) (xy 0.22352 0.00508)
						(xy 0.22606 -0.00508) (xy 0.22733 -0.01651) (xy 0.22733 -0.02667) (xy 0.2286 -0.0381) (xy 0.22733 -0.04953)
						(xy 0.22733 -0.05969) (xy 0.22606 -0.07112) (xy 0.22352 -0.08128) (xy 0.22225 -0.09144) (xy 0.21844 -0.10287)
						(xy 0.2159 -0.11303) (xy 0.21209 -0.12319) (xy 0.20701 -0.13335) (xy 0.2032 -0.14224) (xy 0.19812 -0.1524)
						(xy 0.17272 -0.18796) (xy 0.1651 -0.19558) (xy 0.1651 -0.7366) (xy 0.16256 -0.76835) (xy 0.1524 -0.8001)
						(xy 0.13716 -0.82804) (xy 0.11684 -0.85344) (xy 0.09144 -0.87376) (xy 0.0635 -0.889) (xy 0.03175 -0.89916)
					)
					(width 0)
					(fill yes)
				)
			)
		)
		(pad "96" smd custom
			(at -0.750062 4.100068)
			(size 0.1143 0.1143)
			(layers "B.Cu" "B.Mask" "B.Paste")
			(net "M_A_MA11")
			(options
				(clearance outline)
				(anchor circle)
			)
			(primitives
				(gr_poly
					(pts
						(xy 0 -0.9017) (xy -0.03175 -0.89916) (xy -0.0635 -0.889) (xy -0.09144 -0.87376) (xy -0.11684 -0.85344)
						(xy -0.13716 -0.82804) (xy -0.1524 -0.8001) (xy -0.16256 -0.76835) (xy -0.1651 -0.7366) (xy -0.1651 -0.11938)
						(xy -0.17272 -0.11176) (xy -0.19812 -0.0762) (xy -0.2032 -0.06604) (xy -0.20701 -0.05715) (xy -0.21209 -0.04699)
						(xy -0.2159 -0.03683) (xy -0.21844 -0.02667) (xy -0.22225 -0.01524) (xy -0.22352 -0.00508) (xy -0.22606 0.00508)
						(xy -0.22733 0.01651) (xy -0.22733 0.02667) (xy -0.2286 0.0381) (xy -0.22733 0.04953) (xy -0.22733 0.05969)
						(xy -0.22606 0.07112) (xy -0.22352 0.08128) (xy -0.22225 0.09144) (xy -0.21844 0.10287) (xy -0.2159 0.11303)
						(xy -0.21209 0.12319) (xy -0.20701 0.13335) (xy -0.2032 0.14224) (xy -0.19812 0.1524) (xy -0.17272 0.18796)
						(xy -0.1651 0.19558) (xy -0.1651 0.7366) (xy -0.16256 0.76835) (xy -0.1524 0.8001) (xy -0.13716 0.82804)
						(xy -0.11684 0.85344) (xy -0.09144 0.87376) (xy -0.0635 0.889) (xy -0.03175 0.89916) (xy 0 0.9017)
						(xy 0.03175 0.89916) (xy 0.0635 0.889) (xy 0.09144 0.87376) (xy 0.11684 0.85344) (xy 0.13716 0.82804)
						(xy 0.1524 0.8001) (xy 0.16256 0.76835) (xy 0.1651 0.7366) (xy 0.1651 0.19685) (xy 0.17272 0.18923)
						(xy 0.17907 0.18034) (xy 0.18669 0.17145) (xy 0.19177 0.16256) (xy 0.19812 0.15367) (xy 0.20828 0.13335)
						(xy 0.21971 0.10287) (xy 0.22225 0.09271) (xy 0.22479 0.08128) (xy 0.22606 0.07112) (xy 0.2286 0.05969)
						(xy 0.2286 0.01651) (xy 0.22606 0.00508) (xy 0.22479 -0.00508) (xy 0.22225 -0.01651) (xy 0.21971 -0.02667)
						(xy 0.20828 -0.05715) (xy 0.19812 -0.07747) (xy 0.19177 -0.08636) (xy 0.18669 -0.09525) (xy 0.17907 -0.10414)
						(xy 0.17272 -0.11303) (xy 0.1651 -0.12065) (xy 0.1651 -0.7366) (xy 0.16256 -0.76835) (xy 0.1524 -0.8001)
						(xy 0.13716 -0.82804) (xy 0.11684 -0.85344) (xy 0.09144 -0.87376) (xy 0.0635 -0.889) (xy 0.03175 -0.89916)
					)
					(width 0)
					(fill yes)
				)
			)
		)
		(pad "97" smd custom
			(at -0.450088 -4.100068)
			(size 0.1143 0.1143)
			(layers "B.Cu" "B.Mask" "B.Paste")
			(net "M_A_MA8")
			(options
				(clearance outline)
				(anchor circle)
			)
			(primitives
				(gr_poly
					(pts
						(xy 0 -0.9017) (xy -0.03175 -0.89916) (xy -0.0635 -0.889) (xy -0.09144 -0.87376) (xy -0.11684 -0.85344)
						(xy -0.13716 -0.82804) (xy -0.1524 -0.8001) (xy -0.16256 -0.76835) (xy -0.1651 -0.7366) (xy -0.1651 -0.44958)
						(xy -0.17272 -0.44196) (xy -0.19812 -0.4064) (xy -0.2032 -0.39624) (xy -0.20701 -0.38735) (xy -0.21209 -0.37719)
						(xy -0.2159 -0.36703) (xy -0.21844 -0.35687) (xy -0.22225 -0.34544) (xy -0.22352 -0.33528) (xy -0.22606 -0.32512)
						(xy -0.22733 -0.31369) (xy -0.22733 -0.30353) (xy -0.2286 -0.2921) (xy -0.22733 -0.28067) (xy -0.22733 -0.27051)
						(xy -0.22606 -0.25908) (xy -0.22352 -0.24892) (xy -0.22225 -0.23876) (xy -0.21844 -0.22733) (xy -0.2159 -0.21717)
						(xy -0.21209 -0.20701) (xy -0.20701 -0.19685) (xy -0.2032 -0.18796) (xy -0.19812 -0.1778) (xy -0.17272 -0.14224)
						(xy -0.1651 -0.13462) (xy -0.1651 0.7366) (xy -0.16256 0.76835) (xy -0.1524 0.8001) (xy -0.13716 0.82804)
						(xy -0.11684 0.85344) (xy -0.09144 0.87376) (xy -0.0635 0.889) (xy -0.03175 0.89916) (xy 0 0.9017)
						(xy 0.03175 0.89916) (xy 0.0635 0.889) (xy 0.09144 0.87376) (xy 0.11684 0.85344) (xy 0.13716 0.82804)
						(xy 0.1524 0.8001) (xy 0.16256 0.76835) (xy 0.1651 0.7366) (xy 0.1651 -0.13462) (xy 0.17272 -0.14224)
						(xy 0.19812 -0.1778) (xy 0.2032 -0.18796) (xy 0.20701 -0.19685) (xy 0.21209 -0.20701) (xy 0.2159 -0.21717)
						(xy 0.21844 -0.22733) (xy 0.22225 -0.23876) (xy 0.22352 -0.24892) (xy 0.22606 -0.25908) (xy 0.22733 -0.27051)
						(xy 0.22733 -0.28067) (xy 0.2286 -0.2921) (xy 0.22733 -0.30353) (xy 0.22733 -0.31369) (xy 0.22606 -0.32512)
						(xy 0.22352 -0.33528) (xy 0.22225 -0.34544) (xy 0.21844 -0.35687) (xy 0.2159 -0.36703) (xy 0.21209 -0.37719)
						(xy 0.20701 -0.38735) (xy 0.2032 -0.39624) (xy 0.19812 -0.4064) (xy 0.17272 -0.44196) (xy 0.1651 -0.44958)
						(xy 0.1651 -0.7366) (xy 0.16256 -0.76835) (xy 0.1524 -0.8001) (xy 0.13716 -0.82804) (xy 0.11684 -0.85344)
						(xy 0.09144 -0.87376) (xy 0.0635 -0.889) (xy 0.03175 -0.89916)
					)
					(width 0)
					(fill yes)
				)
			)
		)
	)
)
